# S9S_MB_2U (Grand Teton) — schematic netlist excerpt (pin names and nets, part order shuffled) for the footprints in the layout excerpt that follows; sources: Cadence DE-HDL packaged netlist, KiCad conversion of 03242023_DA0F0TMBIJ0_F0T_Motherboard_J_brd_V01_OCP.brd

R1833  Q_RES  0 5% EMPTY  pkg 0402LF  page 214 : A = FM_JTAG_BMC_MUX_SEL_R ; B = FM_JTAG_BMC_MUX_SEL
PC428  Q_CAP  2.2UF 10V 10% X6S  pkg C0402  page 294 : A = PVCCFA_EHV_CPU1_VDD1 ; B = GND

(kicad_pcb
	(version 20260206)
	(generator "pcbnew")
	(generator_version "10.0")
	(general
		(thickness 1.6)
		(legacy_teardrops no)
	)
	(paper "A4")
	(title_block
		(title "03242023_DA0F0TMBIJ0_F0T_Motherboard_J_brd_V01_OCP.brd")
		(comment 1 "Grand Teton / footprints 606-607 of 6105")
	)
	(layers
		(0 "F.Cu" signal "TOP")
		(4 "In1.Cu" signal "GND")
		(6 "In2.Cu" signal "IN1")
		(8 "In3.Cu" signal "GND1")
		(10 "In4.Cu" signal "IN2")
		(12 "In5.Cu" signal "GND2")
		(14 "In6.Cu" signal "IN3")
		(16 "In7.Cu" signal "GND3")
		(18 "In8.Cu" signal "VCC")
		(20 "In9.Cu" signal "VCC1")
		(22 "In10.Cu" signal "GND4")
		(24 "In11.Cu" signal "IN4")
		(26 "In12.Cu" signal "GND5")
		(28 "In13.Cu" signal "IN5")
		(30 "In14.Cu" signal "GND6")
		(32 "In15.Cu" signal "IN6")
		(34 "In16.Cu" signal "GND7")
		(2 "B.Cu" signal "BOTTOM")
		(9 "F.Adhes" user "F.Adhesive")
		(11 "B.Adhes" user "B.Adhesive")
		(13 "F.Paste" user "Package Geometry/Pastemask Top")
		(15 "B.Paste" user "Package Geometry/Pastemask Bottom")
		(5 "F.SilkS" user "Ref Des/Silkscreen Top")
		(7 "B.SilkS" user "Ref Des/Silkscreen Bottom")
		(1 "F.Mask" user "Board Geometry/Soldermask Top")
		(3 "B.Mask" user "Board Geometry/Soldermask Bottom")
		(17 "Dwgs.User" user "User.Drawings")
		(19 "Cmts.User" user "User.Comments")
		(21 "Eco1.User" user "User.Eco1")
		(23 "Eco2.User" user "User.Eco2")
		(25 "Edge.Cuts" user "Board Geometry/Outline")
		(27 "Margin" user)
		(31 "F.CrtYd" user "Package Geometry/Place Bound Top")
		(29 "B.CrtYd" user "Package Geometry/Place Bound Bottom")
		(35 "F.Fab" user "Ref Des/Assembly Top")
		(33 "B.Fab" user "Ref Des/Assembly Bottom")
	)
	(footprint ""
		(layer "F.Cu")
		(at 189.28588 -126.964948 90)
		(property "Reference" "R1833"
			(at 0 0 90)
			(layer "F.SilkS")
			(hide yes)
			(effects
				(font
					(size 1.27 1.27)
				)
			)
		)
		(property "Value" ""
			(at 0 0 90)
			(layer "F.Fab")
			(effects
				(font
					(size 1.27 1.27)
				)
			)
		)
		(duplicate_pad_numbers_are_jumpers no)
		(fp_line
			(start 0.7874 -0.4064)
			(end 0.7874 0.4064)
			(stroke
				(width 0.1524)
				(type default)
			)
			(layer "F.SilkS")
		)
		(fp_line
			(start -0.7874 -0.4064)
			(end 0.7874 -0.4064)
			(stroke
				(width 0.1524)
				(type default)
			)
			(layer "F.SilkS")
		)
		(fp_line
			(start 0.7874 0.4064)
			(end -0.7874 0.4064)
			(stroke
				(width 0.1524)
				(type default)
			)
			(layer "F.SilkS")
		)
		(fp_line
			(start -0.7874 0.4064)
			(end -0.7874 -0.4064)
			(stroke
				(width 0.1524)
				(type default)
			)
			(layer "F.SilkS")
		)
		(fp_line
			(start -0.12065 -0.305054)
			(end -0.12065 -0.2794)
			(stroke
				(width 0.1)
				(type default)
			)
			(layer "F.Fab")
		)
		(fp_line
			(start -0.67945 -0.305054)
			(end -0.12065 -0.305054)
			(stroke
				(width 0.1)
				(type default)
			)
			(layer "F.Fab")
		)
		(fp_line
			(start 0.67945 -0.3048)
			(end 0.67945 0.3048)
			(stroke
				(width 0.1)
				(type default)
			)
			(layer "F.Fab")
		)
		(fp_line
			(start 0.12065 -0.3048)
			(end 0.67945 -0.3048)
			(stroke
				(width 0.1)
				(type default)
			)
			(layer "F.Fab")
		)
		(fp_line
			(start 0.12065 -0.2794)
			(end 0.12065 -0.3048)
			(stroke
				(width 0.1)
				(type default)
			)
			(layer "F.Fab")
		)
		(fp_line
			(start -0.12065 -0.2794)
			(end 0.12065 -0.2794)
			(stroke
				(width 0.1)
				(type default)
			)
			(layer "F.Fab")
		)
		(fp_line
			(start 0.120396 0.2794)
			(end -0.12065 0.2794)
			(stroke
				(width 0.1)
				(type default)
			)
			(layer "F.Fab")
		)
		(fp_line
			(start -0.12065 0.2794)
			(end -0.12065 0.3048)
			(stroke
				(width 0.1)
				(type default)
			)
			(layer "F.Fab")
		)
		(fp_line
			(start 0.67945 0.3048)
			(end 0.120396 0.3048)
			(stroke
				(width 0.1)
				(type default)
			)
			(layer "F.Fab")
		)
		(fp_line
			(start 0.120396 0.3048)
			(end 0.120396 0.2794)
			(stroke
				(width 0.1)
				(type default)
			)
			(layer "F.Fab")
		)
		(fp_line
			(start -0.12065 0.3048)
			(end -0.67945 0.3048)
			(stroke
				(width 0.1)
				(type default)
			)
			(layer "F.Fab")
		)
		(fp_line
			(start -0.67945 0.3048)
			(end -0.67945 -0.305054)
			(stroke
				(width 0.1)
				(type default)
			)
			(layer "F.Fab")
		)
		(pad "1" smd circle
			(at -0.40005 0 90)
			(size 0 0)
			(layers "F.Cu" "F.Mask" "F.Paste")
			(net "FM_JTAG_BMC_MUX_SEL_R")
		)
		(pad "2" smd circle
			(at 0.40005 0 90)
			(size 0 0)
			(layers "F.Cu" "F.Mask" "F.Paste")
			(net "FM_JTAG_BMC_MUX_SEL")
		)
	)
	(footprint ""
		(layer "F.Cu")
		(at 52.15128 -170.576748 -90)
		(property "Reference" "PC428"
			(at 0 0 270)
			(layer "F.SilkS")
			(hide yes)
			(effects
				(font
					(size 1.27 1.27)
				)
			)
		)
		(property "Value" ""
			(at 0 0 270)
			(layer "F.Fab")
			(effects
				(font
					(size 1.27 1.27)
				)
			)
		)
		(duplicate_pad_numbers_are_jumpers no)
		(fp_line
			(start -0.7874 0.4064)
			(end -0.7874 -0.4064)
			(stroke
				(width 0.1524)
				(type default)
			)
			(layer "F.SilkS")
		)
		(fp_line
			(start 0.7874 0.4064)
			(end -0.7874 0.4064)
			(stroke
				(width 0.1524)
				(type default)
			)
			(layer "F.SilkS")
		)
		(fp_line
			(start -0.7874 -0.4064)
			(end 0.7874 -0.4064)
			(stroke
				(width 0.1524)
				(type default)
			)
			(layer "F.SilkS")
		)
		(fp_line
			(start 0.7874 -0.4064)
			(end 0.7874 0.4064)
			(stroke
				(width 0.1524)
				(type default)
			)
			(layer "F.SilkS")
		)
		(fp_line
			(start -0.67945 0.3048)
			(end -0.67945 -0.305054)
			(stroke
				(width 0.1)
				(type default)
			)
			(layer "F.Fab")
		)
		(fp_line
			(start -0.12065 0.3048)
			(end -0.67945 0.3048)
			(stroke
				(width 0.1)
				(type default)
			)
			(layer "F.Fab")
		)
		(fp_line
			(start 0.120396 0.3048)
			(end 0.120396 0.2794)
			(stroke
				(width 0.1)
				(type default)
			)
			(layer "F.Fab")
		)
		(fp_line
			(start 0.67945 0.3048)
			(end 0.120396 0.3048)
			(stroke
				(width 0.1)
				(type default)
			)
			(layer "F.Fab")
		)
		(fp_line
			(start -0.12065 0.2794)
			(end -0.12065 0.3048)
			(stroke
				(width 0.1)
				(type default)
			)
			(layer "F.Fab")
		)
		(fp_line
			(start 0.120396 0.2794)
			(end -0.12065 0.2794)
			(stroke
				(width 0.1)
				(type default)
			)
			(layer "F.Fab")
		)
		(fp_line
			(start -0.12065 -0.2794)
			(end 0.12065 -0.2794)
			(stroke
				(width 0.1)
				(type default)
			)
			(layer "F.Fab")
		)
		(fp_line
			(start 0.12065 -0.2794)
			(end 0.12065 -0.3048)
			(stroke
				(width 0.1)
				(type default)
			)
			(layer "F.Fab")
		)
		(fp_line
			(start 0.12065 -0.3048)
			(end 0.67945 -0.3048)
			(stroke
				(width 0.1)
				(type default)
			)
			(layer "F.Fab")
		)
		(fp_line
			(start 0.67945 -0.3048)
			(end 0.67945 0.3048)
			(stroke
				(width 0.1)
				(type default)
			)
			(layer "F.Fab")
		)
		(fp_line
			(start -0.67945 -0.305054)
			(end -0.12065 -0.305054)
			(stroke
				(width 0.1)
				(type default)
			)
			(layer "F.Fab")
		)
		(fp_line
			(start -0.12065 -0.305054)
			(end -0.12065 -0.2794)
			(stroke
				(width 0.1)
				(type default)
			)
			(layer "F.Fab")
		)
		(pad "1" smd circle
			(at -0.40005 0 270)
			(size 0 0)
			(layers "F.Cu" "F.Mask" "F.Paste")
			(net "PVCCFA_EHV_CPU1_VDD1")
		)
		(pad "2" smd circle
			(at 0.40005 0 270)
			(size 0 0)
			(layers "F.Cu" "F.Mask" "F.Paste")
			(net "GND")
		)
	)
)
